(kicad_pcb
	(version 20260206)
	(generator "pcbnew")
	(generator_version "10.0")
	(general
		(thickness 1.6)
		(legacy_teardrops no)
	)
	(paper "A4")
	(title_block
		(title "03242023_DA0F0TMBIJ0_F0T_Motherboard_J_brd_V01_OCP.brd")
		(comment 1 "Grand Teton / footprints 4111-4117 of 6105")
	)
	(layers
		(0 "F.Cu" signal "TOP")
		(4 "In1.Cu" signal "GND")
		(6 "In2.Cu" signal "IN1")
		(8 "In3.Cu" signal "GND1")
		(10 "In4.Cu" signal "IN2")
		(12 "In5.Cu" signal "GND2")
		(14 "In6.Cu" signal "IN3")
		(16 "In7.Cu" signal "GND3")
		(18 "In8.Cu" signal "VCC")
		(20 "In9.Cu" signal "VCC1")
		(22 "In10.Cu" signal "GND4")
		(24 "In11.Cu" signal "IN4")
		(26 "In12.Cu" signal "GND5")
		(28 "In13.Cu" signal "IN5")
		(30 "In14.Cu" signal "GND6")
		(32 "In15.Cu" signal "IN6")
		(34 "In16.Cu" signal "GND7")
		(2 "B.Cu" signal "BOTTOM")
		(9 "F.Adhes" user "F.Adhesive")
		(11 "B.Adhes" user "B.Adhesive")
		(13 "F.Paste" user "Package Geometry/Pastemask Top")
		(15 "B.Paste" user "Package Geometry/Pastemask Bottom")
		(5 "F.SilkS" user "Ref Des/Silkscreen Top")
		(7 "B.SilkS" user "Ref Des/Silkscreen Bottom")
		(1 "F.Mask" user "Board Geometry/Soldermask Top")
		(3 "B.Mask" user "Board Geometry/Soldermask Bottom")
		(17 "Dwgs.User" user "User.Drawings")
		(19 "Cmts.User" user "User.Comments")
		(21 "Eco1.User" user "User.Eco1")
		(23 "Eco2.User" user "User.Eco2")
		(25 "Edge.Cuts" user "Board Geometry/Outline")
		(27 "Margin" user)
		(31 "F.CrtYd" user "Package Geometry/Place Bound Top")
		(29 "B.CrtYd" user "Package Geometry/Place Bound Bottom")
		(35 "F.Fab" user "Ref Des/Assembly Top")
		(33 "B.Fab" user "Ref Des/Assembly Bottom")
	)
	(footprint ""
		(layer "F.Cu")
		(at 51.860196 -358.20223 90)
		(property "Reference" "PR1801"
			(at 0 0 90)
			(layer "F.SilkS")
			(hide yes)
			(effects
				(font
					(size 1.27 1.27)
				)
			)
		)
		(property "Value" ""
			(at 0 0 90)
			(layer "F.Fab")
			(effects
				(font
					(size 1.27 1.27)
				)
			)
		)
		(duplicate_pad_numbers_are_jumpers no)
		(fp_line
			(start 0.7874 -0.4064)
			(end 0.7874 0.4064)
			(stroke
				(width 0.1524)
				(type default)
			)
			(layer "F.SilkS")
		)
		(fp_line
			(start -0.7874 -0.4064)
			(end 0.7874 -0.4064)
			(stroke
				(width 0.1524)
				(type default)
			)
			(layer "F.SilkS")
		)
		(fp_line
			(start 0.7874 0.4064)
			(end -0.7874 0.4064)
			(stroke
				(width 0.1524)
				(type default)
			)
			(layer "F.SilkS")
		)
		(fp_line
			(start -0.7874 0.4064)
			(end -0.7874 -0.4064)
			(stroke
				(width 0.1524)
				(type default)
			)
			(layer "F.SilkS")
		)
		(fp_line
			(start -0.12065 -0.305054)
			(end -0.12065 -0.2794)
			(stroke
				(width 0.1)
				(type default)
			)
			(layer "F.Fab")
		)
		(fp_line
			(start -0.67945 -0.305054)
			(end -0.12065 -0.305054)
			(stroke
				(width 0.1)
				(type default)
			)
			(layer "F.Fab")
		)
		(fp_line
			(start 0.67945 -0.3048)
			(end 0.67945 0.3048)
			(stroke
				(width 0.1)
				(type default)
			)
			(layer "F.Fab")
		)
		(fp_line
			(start 0.12065 -0.3048)
			(end 0.67945 -0.3048)
			(stroke
				(width 0.1)
				(type default)
			)
			(layer "F.Fab")
		)
		(fp_line
			(start 0.12065 -0.2794)
			(end 0.12065 -0.3048)
			(stroke
				(width 0.1)
				(type default)
			)
			(layer "F.Fab")
		)
		(fp_line
			(start -0.12065 -0.2794)
			(end 0.12065 -0.2794)
			(stroke
				(width 0.1)
				(type default)
			)
			(layer "F.Fab")
		)
		(fp_line
			(start 0.120396 0.2794)
			(end -0.12065 0.2794)
			(stroke
				(width 0.1)
				(type default)
			)
			(layer "F.Fab")
		)
		(fp_line
			(start -0.12065 0.2794)
			(end -0.12065 0.3048)
			(stroke
				(width 0.1)
				(type default)
			)
			(layer "F.Fab")
		)
		(fp_line
			(start 0.67945 0.3048)
			(end 0.120396 0.3048)
			(stroke
				(width 0.1)
				(type default)
			)
			(layer "F.Fab")
		)
		(fp_line
			(start 0.120396 0.3048)
			(end 0.120396 0.2794)
			(stroke
				(width 0.1)
				(type default)
			)
			(layer "F.Fab")
		)
		(fp_line
			(start -0.12065 0.3048)
			(end -0.67945 0.3048)
			(stroke
				(width 0.1)
				(type default)
			)
			(layer "F.Fab")
		)
		(fp_line
			(start -0.67945 0.3048)
			(end -0.67945 -0.305054)
			(stroke
				(width 0.1)
				(type default)
			)
			(layer "F.Fab")
		)
		(pad "1" smd circle
			(at -0.40005 0 90)
			(size 0 0)
			(layers "F.Cu" "F.Mask" "F.Paste")
			(net "SW_PVCCFA_EHV_FIVRA_CPU1_BOOT2")
		)
		(pad "2" smd circle
			(at 0.40005 0 90)
			(size 0 0)
			(layers "F.Cu" "F.Mask" "F.Paste")
			(net "SW_PVCCFA_EHV_FIVRA_CPU1_BOOT2_")
		)
	)
	(footprint ""
		(layer "F.Cu")
		(at 31.856426 -77.783944 180)
		(property "Reference" "R3145"
			(at 0 0 180)
			(layer "F.SilkS")
			(hide yes)
			(effects
				(font
					(size 1.27 1.27)
				)
			)
		)
		(property "Value" ""
			(at 0 0 180)
			(layer "F.Fab")
			(effects
				(font
					(size 1.27 1.27)
				)
			)
		)
		(duplicate_pad_numbers_are_jumpers no)
		(fp_line
			(start 0.7874 0.4064)
			(end -0.7874 0.4064)
			(stroke
				(width 0.1524)
				(type default)
			)
			(layer "F.SilkS")
		)
		(fp_line
			(start 0.7874 -0.4064)
			(end 0.7874 0.4064)
			(stroke
				(width 0.1524)
				(type default)
			)
			(layer "F.SilkS")
		)
		(fp_line
			(start -0.7874 0.4064)
			(end -0.7874 -0.4064)
			(stroke
				(width 0.1524)
				(type default)
			)
			(layer "F.SilkS")
		)
		(fp_line
			(start -0.7874 -0.4064)
			(end 0.7874 -0.4064)
			(stroke
				(width 0.1524)
				(type default)
			)
			(layer "F.SilkS")
		)
		(fp_line
			(start 0.67945 0.3048)
			(end 0.120396 0.3048)
			(stroke
				(width 0.1)
				(type default)
			)
			(layer "F.Fab")
		)
		(fp_line
			(start 0.67945 -0.3048)
			(end 0.67945 0.3048)
			(stroke
				(width 0.1)
				(type default)
			)
			(layer "F.Fab")
		)
		(fp_line
			(start 0.12065 -0.2794)
			(end 0.12065 -0.3048)
			(stroke
				(width 0.1)
				(type default)
			)
			(layer "F.Fab")
		)
		(fp_line
			(start 0.12065 -0.3048)
			(end 0.67945 -0.3048)
			(stroke
				(width 0.1)
				(type default)
			)
			(layer "F.Fab")
		)
		(fp_line
			(start 0.120396 0.3048)
			(end 0.120396 0.2794)
			(stroke
				(width 0.1)
				(type default)
			)
			(layer "F.Fab")
		)
		(fp_line
			(start 0.120396 0.2794)
			(end -0.12065 0.2794)
			(stroke
				(width 0.1)
				(type default)
			)
			(layer "F.Fab")
		)
		(fp_line
			(start -0.12065 0.3048)
			(end -0.67945 0.3048)
			(stroke
				(width 0.1)
				(type default)
			)
			(layer "F.Fab")
		)
		(fp_line
			(start -0.12065 0.2794)
			(end -0.12065 0.3048)
			(stroke
				(width 0.1)
				(type default)
			)
			(layer "F.Fab")
		)
		(fp_line
			(start -0.12065 -0.2794)
			(end 0.12065 -0.2794)
			(stroke
				(width 0.1)
				(type default)
			)
			(layer "F.Fab")
		)
		(fp_line
			(start -0.12065 -0.305054)
			(end -0.12065 -0.2794)
			(stroke
				(width 0.1)
				(type default)
			)
			(layer "F.Fab")
		)
		(fp_line
			(start -0.67945 0.3048)
			(end -0.67945 -0.305054)
			(stroke
				(width 0.1)
				(type default)
			)
			(layer "F.Fab")
		)
		(fp_line
			(start -0.67945 -0.305054)
			(end -0.12065 -0.305054)
			(stroke
				(width 0.1)
				(type default)
			)
			(layer "F.Fab")
		)
		(pad "1" smd circle
			(at -0.40005 0 180)
			(size 0 0)
			(layers "F.Cu" "F.Mask" "F.Paste")
			(net "P3V3_AUX")
		)
		(pad "2" smd circle
			(at 0.40005 0 180)
			(size 0 0)
			(layers "F.Cu" "F.Mask" "F.Paste")
			(net "HP_LVC3_OCP_V3_2_ATTN_OUT_SW_N")
		)
	)
	(footprint ""
		(layer "F.Cu")
		(at 352.264726 -258.726686 90)
		(property "Reference" "C420"
			(at 0 0 90)
			(layer "F.SilkS")
			(hide yes)
			(effects
				(font
					(size 1.27 1.27)
				)
			)
		)
		(property "Value" ""
			(at 0 0 90)
			(layer "F.Fab")
			(effects
				(font
					(size 1.27 1.27)
				)
			)
		)
		(duplicate_pad_numbers_are_jumpers no)
		(fp_line
			(start 0.7874 -0.4064)
			(end 0.7874 0.4064)
			(stroke
				(width 0.1524)
				(type default)
			)
			(layer "F.SilkS")
		)
		(fp_line
			(start -0.7874 -0.4064)
			(end 0.7874 -0.4064)
			(stroke
				(width 0.1524)
				(type default)
			)
			(layer "F.SilkS")
		)
		(fp_line
			(start 0.7874 0.4064)
			(end -0.7874 0.4064)
			(stroke
				(width 0.1524)
				(type default)
			)
			(layer "F.SilkS")
		)
		(fp_line
			(start -0.7874 0.4064)
			(end -0.7874 -0.4064)
			(stroke
				(width 0.1524)
				(type default)
			)
			(layer "F.SilkS")
		)
		(fp_line
			(start -0.12065 -0.305054)
			(end -0.12065 -0.2794)
			(stroke
				(width 0.1)
				(type default)
			)
			(layer "F.Fab")
		)
		(fp_line
			(start -0.67945 -0.305054)
			(end -0.12065 -0.305054)
			(stroke
				(width 0.1)
				(type default)
			)
			(layer "F.Fab")
		)
		(fp_line
			(start 0.67945 -0.3048)
			(end 0.67945 0.3048)
			(stroke
				(width 0.1)
				(type default)
			)
			(layer "F.Fab")
		)
		(fp_line
			(start 0.12065 -0.3048)
			(end 0.67945 -0.3048)
			(stroke
				(width 0.1)
				(type default)
			)
			(layer "F.Fab")
		)
		(fp_line
			(start 0.12065 -0.2794)
			(end 0.12065 -0.3048)
			(stroke
				(width 0.1)
				(type default)
			)
			(layer "F.Fab")
		)
		(fp_line
			(start -0.12065 -0.2794)
			(end 0.12065 -0.2794)
			(stroke
				(width 0.1)
				(type default)
			)
			(layer "F.Fab")
		)
		(fp_line
			(start 0.120396 0.2794)
			(end -0.12065 0.2794)
			(stroke
				(width 0.1)
				(type default)
			)
			(layer "F.Fab")
		)
		(fp_line
			(start -0.12065 0.2794)
			(end -0.12065 0.3048)
			(stroke
				(width 0.1)
				(type default)
			)
			(layer "F.Fab")
		)
		(fp_line
			(start 0.67945 0.3048)
			(end 0.120396 0.3048)
			(stroke
				(width 0.1)
				(type default)
			)
			(layer "F.Fab")
		)
		(fp_line
			(start 0.120396 0.3048)
			(end 0.120396 0.2794)
			(stroke
				(width 0.1)
				(type default)
			)
			(layer "F.Fab")
		)
		(fp_line
			(start -0.12065 0.3048)
			(end -0.67945 0.3048)
			(stroke
				(width 0.1)
				(type default)
			)
			(layer "F.Fab")
		)
		(fp_line
			(start -0.67945 0.3048)
			(end -0.67945 -0.305054)
			(stroke
				(width 0.1)
				(type default)
			)
			(layer "F.Fab")
		)
		(pad "1" smd circle
			(at -0.40005 0 90)
			(size 0 0)
			(layers "F.Cu" "F.Mask" "F.Paste")
			(net "PVCCFA_EHV_CPU0")
		)
		(pad "2" smd circle
			(at 0.40005 0 90)
			(size 0 0)
			(layers "F.Cu" "F.Mask" "F.Paste")
			(net "GND")
		)
	)
	(footprint ""
		(layer "F.Cu")
		(at 90.037158 -408.517344 -90)
		(property "Reference" "C683"
			(at 0 0 270)
			(layer "F.SilkS")
			(hide yes)
			(effects
				(font
					(size 1.27 1.27)
				)
			)
		)
		(property "Value" ""
			(at 0 0 270)
			(layer "F.Fab")
			(effects
				(font
					(size 1.27 1.27)
				)
			)
		)
		(duplicate_pad_numbers_are_jumpers no)
		(fp_line
			(start -0.299974 0.150114)
			(end -0.299974 -0.150114)
			(stroke
				(width 0.1)
				(type default)
			)
			(layer "F.Fab")
		)
		(fp_line
			(start 0.299974 0.150114)
			(end -0.299974 0.150114)
			(stroke
				(width 0.1)
				(type default)
			)
			(layer "F.Fab")
		)
		(fp_line
			(start -0.299974 -0.150114)
			(end 0.299974 -0.150114)
			(stroke
				(width 0.1)
				(type default)
			)
			(layer "F.Fab")
		)
		(fp_line
			(start 0.299974 -0.150114)
			(end 0.299974 0.150114)
			(stroke
				(width 0.1)
				(type default)
			)
			(layer "F.Fab")
		)
		(pad "1" smd rect
			(at -0.2667 0 270)
			(size 0.3048 0.381)
			(layers "F.Cu" "F.Mask" "F.Paste")
			(net "P5E_CPU1_PE4_TX_C_DP<13>")
		)
		(pad "2" smd rect
			(at 0.2667 0 270)
			(size 0.3048 0.381)
			(layers "F.Cu" "F.Mask" "F.Paste")
			(net "P5E_CPU1_PE4_TX_DP<13>")
		)
	)
	(footprint ""
		(layer "F.Cu")
		(at 436.224172 -32.173418 90)
		(property "Reference" "R3872"
			(at 0 0 90)
			(layer "F.SilkS")
			(hide yes)
			(effects
				(font
					(size 1.27 1.27)
				)
			)
		)
		(property "Value" ""
			(at 0 0 90)
			(layer "F.Fab")
			(effects
				(font
					(size 1.27 1.27)
				)
			)
		)
		(duplicate_pad_numbers_are_jumpers no)
		(fp_line
			(start 0.7874 -0.4064)
			(end 0.7874 0.4064)
			(stroke
				(width 0.1524)
				(type default)
			)
			(layer "F.SilkS")
		)
		(fp_line
			(start -0.7874 -0.4064)
			(end 0.7874 -0.4064)
			(stroke
				(width 0.1524)
				(type default)
			)
			(layer "F.SilkS")
		)
		(fp_line
			(start 0.7874 0.4064)
			(end -0.7874 0.4064)
			(stroke
				(width 0.1524)
				(type default)
			)
			(layer "F.SilkS")
		)
		(fp_line
			(start -0.7874 0.4064)
			(end -0.7874 -0.4064)
			(stroke
				(width 0.1524)
				(type default)
			)
			(layer "F.SilkS")
		)
		(fp_line
			(start -0.12065 -0.305054)
			(end -0.12065 -0.2794)
			(stroke
				(width 0.1)
				(type default)
			)
			(layer "F.Fab")
		)
		(fp_line
			(start -0.67945 -0.305054)
			(end -0.12065 -0.305054)
			(stroke
				(width 0.1)
				(type default)
			)
			(layer "F.Fab")
		)
		(fp_line
			(start 0.67945 -0.3048)
			(end 0.67945 0.3048)
			(stroke
				(width 0.1)
				(type default)
			)
			(layer "F.Fab")
		)
		(fp_line
			(start 0.12065 -0.3048)
			(end 0.67945 -0.3048)
			(stroke
				(width 0.1)
				(type default)
			)
			(layer "F.Fab")
		)
		(fp_line
			(start 0.12065 -0.2794)
			(end 0.12065 -0.3048)
			(stroke
				(width 0.1)
				(type default)
			)
			(layer "F.Fab")
		)
		(fp_line
			(start -0.12065 -0.2794)
			(end 0.12065 -0.2794)
			(stroke
				(width 0.1)
				(type default)
			)
			(layer "F.Fab")
		)
		(fp_line
			(start 0.120396 0.2794)
			(end -0.12065 0.2794)
			(stroke
				(width 0.1)
				(type default)
			)
			(layer "F.Fab")
		)
		(fp_line
			(start -0.12065 0.2794)
			(end -0.12065 0.3048)
			(stroke
				(width 0.1)
				(type default)
			)
			(layer "F.Fab")
		)
		(fp_line
			(start 0.67945 0.3048)
			(end 0.120396 0.3048)
			(stroke
				(width 0.1)
				(type default)
			)
			(layer "F.Fab")
		)
		(fp_line
			(start 0.120396 0.3048)
			(end 0.120396 0.2794)
			(stroke
				(width 0.1)
				(type default)
			)
			(layer "F.Fab")
		)
		(fp_line
			(start -0.12065 0.3048)
			(end -0.67945 0.3048)
			(stroke
				(width 0.1)
				(type default)
			)
			(layer "F.Fab")
		)
		(fp_line
			(start -0.67945 0.3048)
			(end -0.67945 -0.305054)
			(stroke
				(width 0.1)
				(type default)
			)
			(layer "F.Fab")
		)
		(pad "1" smd circle
			(at -0.40005 0 90)
			(size 0 0)
			(layers "F.Cu" "F.Mask" "F.Paste")
			(net "P12V_OCP_IMON_1")
		)
		(pad "2" smd circle
			(at 0.40005 0 90)
			(size 0 0)
			(layers "F.Cu" "F.Mask" "F.Paste")
			(net "P12V_OCP_SFF_ISENSE_MPS_TIC")
		)
	)
	(footprint ""
		(layer "F.Cu")
		(at 105.39222 -294.01008 180)
		(property "Reference" "C255"
			(at 0 0 180)
			(layer "F.SilkS")
			(hide yes)
			(effects
				(font
					(size 1.27 1.27)
				)
			)
		)
		(property "Value" ""
			(at 0 0 180)
			(layer "F.Fab")
			(effects
				(font
					(size 1.27 1.27)
				)
			)
		)
		(duplicate_pad_numbers_are_jumpers no)
		(fp_line
			(start 1.524 0.762)
			(end -1.524 0.762)
			(stroke
				(width 0.1524)
				(type default)
			)
			(layer "F.SilkS")
		)
		(fp_line
			(start 1.524 -0.762)
			(end 1.524 0.762)
			(stroke
				(width 0.1524)
				(type default)
			)
			(layer "F.SilkS")
		)
		(fp_line
			(start -1.524 0.762)
			(end -1.524 -0.762)
			(stroke
				(width 0.1524)
				(type default)
			)
			(layer "F.SilkS")
		)
		(fp_line
			(start -1.524 -0.762)
			(end 1.524 -0.762)
			(stroke
				(width 0.1524)
				(type default)
			)
			(layer "F.SilkS")
		)
		(fp_line
			(start 1.1049 0.724916)
			(end 1.1049 -0.724916)
			(stroke
				(width 0.1)
				(type default)
			)
			(layer "F.Fab")
		)
		(fp_line
			(start 1.1049 -0.724916)
			(end -1.1049 -0.724916)
			(stroke
				(width 0.1)
				(type default)
			)
			(layer "F.Fab")
		)
		(fp_line
			(start -1.1049 0.724916)
			(end 1.1049 0.724916)
			(stroke
				(width 0.1)
				(type default)
			)
			(layer "F.Fab")
		)
		(fp_line
			(start -1.1049 -0.724916)
			(end -1.1049 0.724916)
			(stroke
				(width 0.1)
				(type default)
			)
			(layer "F.Fab")
		)
		(pad "1" smd rect
			(at -0.889 0)
			(size 1.016 1.27)
			(layers "F.Cu" "F.Mask" "F.Paste")
			(net "PVCCIN_CPU1")
		)
		(pad "2" smd rect
			(at 0.889 0)
			(size 1.016 1.27)
			(layers "F.Cu" "F.Mask" "F.Paste")
			(net "GND")
		)
	)
	(footprint ""
		(layer "F.Cu")
		(at 17.737582 -423.629836 -90)
		(property "Reference" "R3517"
			(at 0 0 270)
			(layer "F.SilkS")
			(hide yes)
			(effects
				(font
					(size 1.27 1.27)
				)
			)
		)
		(property "Value" ""
			(at 0 0 270)
			(layer "F.Fab")
			(effects
				(font
					(size 1.27 1.27)
				)
			)
		)
		(duplicate_pad_numbers_are_jumpers no)
		(fp_line
			(start -0.7874 0.4064)
			(end -0.7874 -0.4064)
			(stroke
				(width 0.1524)
				(type default)
			)
			(layer "F.SilkS")
		)
		(fp_line
			(start 0.7874 0.4064)
			(end -0.7874 0.4064)
			(stroke
				(width 0.1524)
				(type default)
			)
			(layer "F.SilkS")
		)
		(fp_line
			(start -0.7874 -0.4064)
			(end 0.7874 -0.4064)
			(stroke
				(width 0.1524)
				(type default)
			)
			(layer "F.SilkS")
		)
		(fp_line
			(start 0.7874 -0.4064)
			(end 0.7874 0.4064)
			(stroke
				(width 0.1524)
				(type default)
			)
			(layer "F.SilkS")
		)
		(fp_line
			(start -0.67945 0.3048)
			(end -0.67945 -0.305054)
			(stroke
				(width 0.1)
				(type default)
			)
			(layer "F.Fab")
		)
		(fp_line
			(start -0.12065 0.3048)
			(end -0.67945 0.3048)
			(stroke
				(width 0.1)
				(type default)
			)
			(layer "F.Fab")
		)
		(fp_line
			(start 0.120396 0.3048)
			(end 0.120396 0.2794)
			(stroke
				(width 0.1)
				(type default)
			)
			(layer "F.Fab")
		)
		(fp_line
			(start 0.67945 0.3048)
			(end 0.120396 0.3048)
			(stroke
				(width 0.1)
				(type default)
			)
			(layer "F.Fab")
		)
		(fp_line
			(start -0.12065 0.2794)
			(end -0.12065 0.3048)
			(stroke
				(width 0.1)
				(type default)
			)
			(layer "F.Fab")
		)
		(fp_line
			(start 0.120396 0.2794)
			(end -0.12065 0.2794)
			(stroke
				(width 0.1)
				(type default)
			)
			(layer "F.Fab")
		)
		(fp_line
			(start -0.12065 -0.2794)
			(end 0.12065 -0.2794)
			(stroke
				(width 0.1)
				(type default)
			)
			(layer "F.Fab")
		)
		(fp_line
			(start 0.12065 -0.2794)
			(end 0.12065 -0.3048)
			(stroke
				(width 0.1)
				(type default)
			)
			(layer "F.Fab")
		)
		(fp_line
			(start 0.12065 -0.3048)
			(end 0.67945 -0.3048)
			(stroke
				(width 0.1)
				(type default)
			)
			(layer "F.Fab")
		)
		(fp_line
			(start 0.67945 -0.3048)
			(end 0.67945 0.3048)
			(stroke
				(width 0.1)
				(type default)
			)
			(layer "F.Fab")
		)
		(fp_line
			(start -0.67945 -0.305054)
			(end -0.12065 -0.305054)
			(stroke
				(width 0.1)
				(type default)
			)
			(layer "F.Fab")
		)
		(fp_line
			(start -0.12065 -0.305054)
			(end -0.12065 -0.2794)
			(stroke
				(width 0.1)
				(type default)
			)
			(layer "F.Fab")
		)
		(pad "1" smd circle
			(at -0.40005 0 270)
			(size 0 0)
			(layers "F.Cu" "F.Mask" "F.Paste")
			(net "GPU_PEX_STRAP1")
		)
		(pad "2" smd circle
			(at 0.40005 0 270)
			(size 0 0)
			(layers "F.Cu" "F.Mask" "F.Paste")
			(net "GPU_PEX_STRAP1_R")
		)
	)
)
